# T6G (Grand Teton) — schematic netlist excerpt (pin names and nets, part order shuffled) for the footprints in the layout excerpt that follows; sources: Cadence DE-HDL packaged netlist, KiCad conversion of 04192023_DAF0TMB3IC0_F0TG_MB_C_brd_V02_OCP.brd

C1011  Q_CAP  0.1UF 10V 10% X7S  pkg C0201  page 312 : A = P0V9_CPU0_RT3_2A ; B = GND
PR67  Q_RES  1.96K 1% CHIP  pkg 0402LF  page 200 : A = PVDDCR_CPU1_P0_EN1_ADDR_CFG ; B = GND
C167  Q_CAP  10UF 25V 10% X6S  pkg C0805  page 96 : A = P12V_MEM_CPU0 ; B = GND

(kicad_pcb
	(version 20260206)
	(generator "pcbnew")
	(generator_version "10.0")
	(general
		(thickness 1.6)
		(legacy_teardrops no)
	)
	(paper "A4")
	(title_block
		(title "04192023_DAF0TMB3IC0_F0TG_MB_C_brd_V02_OCP.brd")
		(comment 1 "Grand Teton / footprints 6556-6558 of 8354")
	)
	(layers
		(0 "F.Cu" signal "TOP")
		(4 "In1.Cu" signal "GND")
		(6 "In2.Cu" signal "IN1")
		(8 "In3.Cu" signal "GND1")
		(10 "In4.Cu" signal "IN2")
		(12 "In5.Cu" signal "GND2")
		(14 "In6.Cu" signal "IN3")
		(16 "In7.Cu" signal "GND3")
		(18 "In8.Cu" signal "VCC")
		(20 "In9.Cu" signal "VCC1")
		(22 "In10.Cu" signal "GND4")
		(24 "In11.Cu" signal "IN4")
		(26 "In12.Cu" signal "GND5")
		(28 "In13.Cu" signal "IN5")
		(30 "In14.Cu" signal "GND6")
		(32 "In15.Cu" signal "IN6")
		(34 "In16.Cu" signal "GND7")
		(2 "B.Cu" signal "BOTTOM")
		(9 "F.Adhes" user "F.Adhesive")
		(11 "B.Adhes" user "B.Adhesive")
		(13 "F.Paste" user "Package Geometry/Pastemask Top")
		(15 "B.Paste" user "Package Geometry/Pastemask Bottom")
		(5 "F.SilkS" user "Ref Des/Silkscreen Top")
		(7 "B.SilkS" user "Ref Des/Silkscreen Bottom")
		(1 "F.Mask" user "Board Geometry/Soldermask Top")
		(3 "B.Mask" user "Board Geometry/Soldermask Bottom")
		(17 "Dwgs.User" user "User.Drawings")
		(19 "Cmts.User" user "User.Comments")
		(21 "Eco1.User" user "User.Eco1")
		(23 "Eco2.User" user "User.Eco2")
		(25 "Edge.Cuts" user "Board Geometry/Outline")
		(27 "Margin" user)
		(31 "F.CrtYd" user "Package Geometry/Place Bound Top")
		(29 "B.CrtYd" user "Package Geometry/Place Bound Bottom")
		(35 "F.Fab" user "Ref Des/Assembly Top")
		(33 "B.Fab" user "Ref Des/Assembly Bottom")
	)
	(footprint ""
		(layer "B.Cu")
		(at 442.543946 -192.660016 180)
		(property "Reference" "C167"
			(at 0 0 0)
			(layer "B.SilkS")
			(hide yes)
			(effects
				(font
					(size 1.27 1.27)
				)
				(justify mirror)
			)
		)
		(property "Value" ""
			(at 0 0 0)
			(layer "B.Fab")
			(effects
				(font
					(size 1.27 1.27)
				)
				(justify mirror)
			)
		)
		(duplicate_pad_numbers_are_jumpers no)
		(fp_line
			(start 1.524 0.762)
			(end 1.524 -0.762)
			(stroke
				(width 0.1524)
				(type default)
			)
			(layer "B.SilkS")
		)
		(fp_line
			(start 1.524 -0.762)
			(end -1.524 -0.762)
			(stroke
				(width 0.1524)
				(type default)
			)
			(layer "B.SilkS")
		)
		(fp_line
			(start -1.524 0.762)
			(end 1.524 0.762)
			(stroke
				(width 0.1524)
				(type default)
			)
			(layer "B.SilkS")
		)
		(fp_line
			(start -1.524 -0.762)
			(end -1.524 0.762)
			(stroke
				(width 0.1524)
				(type default)
			)
			(layer "B.SilkS")
		)
		(fp_line
			(start 1.1049 0.724916)
			(end -1.1049 0.724916)
			(stroke
				(width 0.1)
				(type default)
			)
			(layer "B.Fab")
		)
		(fp_line
			(start 1.1049 -0.724916)
			(end 1.1049 0.724916)
			(stroke
				(width 0.1)
				(type default)
			)
			(layer "B.Fab")
		)
		(fp_line
			(start -1.1049 0.724916)
			(end -1.1049 -0.724916)
			(stroke
				(width 0.1)
				(type default)
			)
			(layer "B.Fab")
		)
		(fp_line
			(start -1.1049 -0.724916)
			(end 1.1049 -0.724916)
			(stroke
				(width 0.1)
				(type default)
			)
			(layer "B.Fab")
		)
		(pad "1" smd rect
			(at 0.889 0 180)
			(size 1.016 1.27)
			(layers "B.Cu" "B.Mask" "B.Paste")
			(net "P12V_MEM_CPU0")
		)
		(pad "2" smd rect
			(at -0.889 0 180)
			(size 1.016 1.27)
			(layers "B.Cu" "B.Mask" "B.Paste")
			(net "GND")
		)
	)
	(footprint ""
		(layer "B.Cu")
		(at 312.547 -359.918)
		(property "Reference" "PR67"
			(at 0 0 0)
			(layer "B.SilkS")
			(hide yes)
			(effects
				(font
					(size 1.27 1.27)
				)
				(justify mirror)
			)
		)
		(property "Value" ""
			(at 0 0 0)
			(layer "B.Fab")
			(effects
				(font
					(size 1.27 1.27)
				)
				(justify mirror)
			)
		)
		(duplicate_pad_numbers_are_jumpers no)
		(fp_line
			(start -0.7874 -0.4064)
			(end -0.7874 0.4064)
			(stroke
				(width 0.1524)
				(type default)
			)
			(layer "B.SilkS")
		)
		(fp_line
			(start -0.7874 0.4064)
			(end 0.7874 0.4064)
			(stroke
				(width 0.1524)
				(type default)
			)
			(layer "B.SilkS")
		)
		(fp_line
			(start 0.7874 -0.4064)
			(end -0.7874 -0.4064)
			(stroke
				(width 0.1524)
				(type default)
			)
			(layer "B.SilkS")
		)
		(fp_line
			(start 0.7874 0.4064)
			(end 0.7874 -0.4064)
			(stroke
				(width 0.1524)
				(type default)
			)
			(layer "B.SilkS")
		)
		(fp_line
			(start -0.67945 -0.3048)
			(end -0.67945 0.3048)
			(stroke
				(width 0.1)
				(type default)
			)
			(layer "B.Fab")
		)
		(fp_line
			(start -0.67945 0.3048)
			(end -0.120396 0.3048)
			(stroke
				(width 0.1)
				(type default)
			)
			(layer "B.Fab")
		)
		(fp_line
			(start -0.12065 -0.3048)
			(end -0.67945 -0.3048)
			(stroke
				(width 0.1)
				(type default)
			)
			(layer "B.Fab")
		)
		(fp_line
			(start -0.12065 -0.2794)
			(end -0.12065 -0.3048)
			(stroke
				(width 0.1)
				(type default)
			)
			(layer "B.Fab")
		)
		(fp_line
			(start -0.120396 0.2794)
			(end 0.12065 0.2794)
			(stroke
				(width 0.1)
				(type default)
			)
			(layer "B.Fab")
		)
		(fp_line
			(start -0.120396 0.3048)
			(end -0.120396 0.2794)
			(stroke
				(width 0.1)
				(type default)
			)
			(layer "B.Fab")
		)
		(fp_line
			(start 0.12065 -0.305054)
			(end 0.12065 -0.2794)
			(stroke
				(width 0.1)
				(type default)
			)
			(layer "B.Fab")
		)
		(fp_line
			(start 0.12065 -0.2794)
			(end -0.12065 -0.2794)
			(stroke
				(width 0.1)
				(type default)
			)
			(layer "B.Fab")
		)
		(fp_line
			(start 0.12065 0.2794)
			(end 0.12065 0.3048)
			(stroke
				(width 0.1)
				(type default)
			)
			(layer "B.Fab")
		)
		(fp_line
			(start 0.12065 0.3048)
			(end 0.67945 0.3048)
			(stroke
				(width 0.1)
				(type default)
			)
			(layer "B.Fab")
		)
		(fp_line
			(start 0.67945 -0.305054)
			(end 0.12065 -0.305054)
			(stroke
				(width 0.1)
				(type default)
			)
			(layer "B.Fab")
		)
		(fp_line
			(start 0.67945 0.3048)
			(end 0.67945 -0.305054)
			(stroke
				(width 0.1)
				(type default)
			)
			(layer "B.Fab")
		)
		(pad "1" smd circle
			(at 0.40005 0 180)
			(size 0 0)
			(layers "B.Cu" "B.Mask" "B.Paste")
			(net "PVDDCR_CPU1_P0_EN1_ADDR_CFG")
		)
		(pad "2" smd circle
			(at -0.40005 0 180)
			(size 0 0)
			(layers "B.Cu" "B.Mask" "B.Paste")
			(net "GND")
		)
	)
	(footprint ""
		(layer "B.Cu")
		(at 373.018558 -396.393162 -90)
		(property "Reference" "C1011"
			(at 0 0 90)
			(layer "B.SilkS")
			(hide yes)
			(effects
				(font
					(size 1.27 1.27)
				)
				(justify mirror)
			)
		)
		(property "Value" ""
			(at 0 0 90)
			(layer "B.Fab")
			(effects
				(font
					(size 1.27 1.27)
				)
				(justify mirror)
			)
		)
		(duplicate_pad_numbers_are_jumpers no)
		(fp_line
			(start -0.299974 0.150114)
			(end 0.299974 0.150114)
			(stroke
				(width 0.1)
				(type default)
			)
			(layer "B.Fab")
		)
		(fp_line
			(start 0.299974 0.150114)
			(end 0.299974 -0.150114)
			(stroke
				(width 0.1)
				(type default)
			)
			(layer "B.Fab")
		)
		(fp_line
			(start -0.299974 -0.150114)
			(end -0.299974 0.150114)
			(stroke
				(width 0.1)
				(type default)
			)
			(layer "B.Fab")
		)
		(fp_line
			(start 0.299974 -0.150114)
			(end -0.299974 -0.150114)
			(stroke
				(width 0.1)
				(type default)
			)
			(layer "B.Fab")
		)
		(pad "1" smd rect
			(at 0.2667 0 90)
			(size 0.3048 0.381)
			(layers "B.Cu" "B.Mask" "B.Paste")
			(net "P0V9_CPU0_RT3_2A")
		)
		(pad "2" smd rect
			(at -0.2667 0 90)
			(size 0.3048 0.381)
			(layers "B.Cu" "B.Mask" "B.Paste")
			(net "GND")
		)
	)
)
